(kicad_pcb
	(version 20260206)
	(generator "pcbnew")
	(generator_version "10.0")
	(general
		(thickness 1.6)
		(legacy_teardrops no)
	)
	(paper "A4")
	(title_block
		(title "panther-plus-userver — 13130-1b_20150205.brd")
		(comment 1 "Honey Badger (Wiwynn) / footprints 1473-1480 of 1509")
	)
	(layers
		(0 "F.Cu" signal "TOP")
		(4 "In1.Cu" signal "L2")
		(6 "In2.Cu" signal "L3")
		(8 "In3.Cu" signal "L4")
		(10 "In4.Cu" signal "L5")
		(12 "In5.Cu" signal "L6")
		(14 "In6.Cu" signal "L7")
		(16 "In7.Cu" signal "L8")
		(18 "In8.Cu" signal "L9")
		(20 "In9.Cu" signal "L10")
		(22 "In10.Cu" signal "L11")
		(2 "B.Cu" signal "BOTTOM")
		(9 "F.Adhes" user "F.Adhesive")
		(11 "B.Adhes" user "B.Adhesive")
		(13 "F.Paste" user "Package Geometry/Pastemask Top")
		(15 "B.Paste" user "Package Geometry/Pastemask Bottom")
		(5 "F.SilkS" user "Ref Des/Silkscreen Top")
		(7 "B.SilkS" user "Ref Des/Silkscreen Bottom")
		(1 "F.Mask" user "Board Geometry/Soldermask Top")
		(3 "B.Mask" user "Board Geometry/Soldermask Bottom")
		(17 "Dwgs.User" user "User.Drawings")
		(19 "Cmts.User" user "User.Comments")
		(21 "Eco1.User" user "User.Eco1")
		(23 "Eco2.User" user "User.Eco2")
		(25 "Edge.Cuts" user "Board Geometry/Outline")
		(27 "Margin" user)
		(31 "F.CrtYd" user "Package Geometry/Place Bound Top")
		(29 "B.CrtYd" user "Package Geometry/Place Bound Bottom")
		(35 "F.Fab" user "Ref Des/Assembly Top")
		(33 "B.Fab" user "Ref Des/Assembly Bottom")
	)
	(footprint ""
		(layer "B.Cu")
		(at 25.4 -15.494)
		(property "Reference" "TP50"
			(at 0 0 0)
			(layer "B.SilkS")
			(hide yes)
			(effects
				(font
					(size 1.27 1.27)
				)
				(justify mirror)
			)
		)
		(property "Value" "TPAD32-GP"
			(at 0 -3.166364 0)
			(unlocked yes)
			(layer "B.Fab")
			(hide yes)
			(effects
				(font
					(size 1.016 1.016)
					(thickness 0.1524)
				)
				(justify mirror)
			)
		)
		(property "Device Type" "TPAD32"
			(at 0 -4.690618 0)
			(unlocked yes)
			(layer "B.Fab")
			(hide yes)
			(effects
				(font
					(size 1.016 1.016)
					(thickness 0.1524)
				)
				(justify mirror)
			)
		)
		(duplicate_pad_numbers_are_jumpers no)
		(fp_poly
			(pts
				(arc
					(start 0.7112 0)
					(mid -0.7112 0)
					(end 0.7112 0)
				)
			)
			(stroke
				(width 0)
				(type default)
			)
			(fill no)
			(layer "B.CrtYd")
		)
		(fp_poly
			(pts
				(arc
					(start 0.7112 0)
					(mid -0.7112 0)
					(end 0.7112 0)
				)
			)
			(stroke
				(width 0)
				(type default)
			)
			(fill no)
			(layer "B.Fab")
		)
		(pad "1" smd circle
			(at 0 0 180)
			(size 0.8128 0.8128)
			(layers "B.Cu" "B.Mask" "B.Paste")
			(net "XDP_SOC_CPU_TCK")
		)
	)
	(footprint ""
		(layer "B.Cu")
		(at 30.226 -12.7)
		(property "Reference" "C270"
			(at 0 0 0)
			(layer "B.SilkS")
			(hide yes)
			(effects
				(font
					(size 1.27 1.27)
				)
				(justify mirror)
			)
		)
		(property "Value" "SCD1U16V2KX-3GP"
			(at -1.1811 -2.7051 0)
			(unlocked yes)
			(layer "B.Fab")
			(hide yes)
			(effects
				(font
					(size 1.016 1.016)
					(thickness 0.1524)
				)
				(justify mirror)
			)
		)
		(property "Device Type" "C402H22"
			(at -1.1811 -4.2291 0)
			(unlocked yes)
			(layer "B.Fab")
			(hide yes)
			(effects
				(font
					(size 1.016 1.016)
					(thickness 0.1524)
				)
				(justify mirror)
			)
		)
		(duplicate_pad_numbers_are_jumpers no)
		(fp_rect
			(start 0.381 0.7366)
			(end -0.381 -0.7366)
			(stroke
				(width 0)
				(type default)
			)
			(fill no)
			(layer "B.CrtYd")
		)
		(fp_rect
			(start 0.381 0.7366)
			(end -0.381 -0.7366)
			(stroke
				(width 0)
				(type default)
			)
			(fill no)
			(layer "B.Fab")
		)
		(pad "1" smd custom
			(at 0 -0.4572 180)
			(size 0.1143 0.1143)
			(layers "B.Cu" "B.Mask" "B.Paste")
			(net "P2E_CPU_ETH10G_C_TX_DP8")
			(options
				(clearance outline)
				(anchor circle)
			)
			(primitives
				(gr_poly
					(pts
						(arc
							(start -0.254 0.1778)
							(mid -0.239121 0.213721)
							(end -0.2032 0.2286)
						)
						(arc
							(start 0.2032 0.2286)
							(mid 0.239121 0.213721)
							(end 0.254 0.1778)
						)
						(arc
							(start 0.254 -0.1778)
							(mid 0.239121 -0.213721)
							(end 0.2032 -0.2286)
						)
						(arc
							(start -0.2032 -0.2286)
							(mid -0.239121 -0.213721)
							(end -0.254 -0.1778)
						)
					)
					(width 0)
					(fill yes)
				)
			)
		)
		(pad "2" smd custom
			(at 0 0.4572 180)
			(size 0.1143 0.1143)
			(layers "B.Cu" "B.Mask" "B.Paste")
			(net "P2E_CPU_ETH10G_TX_DP8")
			(options
				(clearance outline)
				(anchor circle)
			)
			(primitives
				(gr_poly
					(pts
						(arc
							(start -0.254 0.1778)
							(mid -0.239121 0.213721)
							(end -0.2032 0.2286)
						)
						(arc
							(start 0.2032 0.2286)
							(mid 0.239121 0.213721)
							(end 0.254 0.1778)
						)
						(arc
							(start 0.254 -0.1778)
							(mid 0.239121 -0.213721)
							(end 0.2032 -0.2286)
						)
						(arc
							(start -0.2032 -0.2286)
							(mid -0.239121 -0.213721)
							(end -0.254 -0.1778)
						)
					)
					(width 0)
					(fill yes)
				)
			)
		)
	)
	(footprint ""
		(layer "B.Cu")
		(at 95.885 -36.83)
		(property "Reference" "R333"
			(at 0 0 0)
			(layer "B.SilkS")
			(hide yes)
			(effects
				(font
					(size 1.27 1.27)
				)
				(justify mirror)
			)
		)
		(property "Value" "100KR2F-L1-GP"
			(at -0.064008 -3.993896 0)
			(unlocked yes)
			(layer "B.Fab")
			(hide yes)
			(effects
				(font
					(size 1.016 1.016)
					(thickness 0.1524)
				)
				(justify mirror)
			)
		)
		(property "Device Type" "R402H16"
			(at -0.064008 -5.517896 0)
			(unlocked yes)
			(layer "B.Fab")
			(hide yes)
			(effects
				(font
					(size 1.016 1.016)
					(thickness 0.1524)
				)
				(justify mirror)
			)
		)
		(duplicate_pad_numbers_are_jumpers no)
		(fp_rect
			(start 0.381 0.8382)
			(end -0.381 -0.8382)
			(stroke
				(width 0)
				(type default)
			)
			(fill no)
			(layer "B.CrtYd")
		)
		(fp_rect
			(start 0.381 0.8382)
			(end -0.381 -0.8382)
			(stroke
				(width 0)
				(type default)
			)
			(fill no)
			(layer "B.Fab")
		)
		(pad "1" smd custom
			(at 0 -0.4318 180)
			(size 0.127 0.127)
			(layers "B.Cu" "B.Mask" "B.Paste")
			(net "VSSRAMCPUSI1_SENSE")
			(options
				(clearance outline)
				(anchor circle)
			)
			(primitives
				(gr_poly
					(pts
						(arc
							(start -0.2032 0.2794)
							(mid -0.239121 0.264521)
							(end -0.254 0.2286)
						)
						(arc
							(start -0.254 -0.2286)
							(mid -0.239121 -0.264521)
							(end -0.2032 -0.2794)
						)
						(arc
							(start 0.2032 -0.2794)
							(mid 0.239121 -0.264521)
							(end 0.254 -0.2286)
						)
						(arc
							(start 0.254 0.2286)
							(mid 0.239121 0.264521)
							(end 0.2032 0.2794)
						)
					)
					(width 0)
					(fill yes)
				)
			)
		)
		(pad "2" smd custom
			(at 0 0.4318 180)
			(size 0.127 0.127)
			(layers "B.Cu" "B.Mask" "B.Paste")
			(net "GND")
			(options
				(clearance outline)
				(anchor circle)
			)
			(primitives
				(gr_poly
					(pts
						(arc
							(start -0.2032 0.2794)
							(mid -0.239121 0.264521)
							(end -0.254 0.2286)
						)
						(arc
							(start -0.254 -0.2286)
							(mid -0.239121 -0.264521)
							(end -0.2032 -0.2794)
						)
						(arc
							(start 0.2032 -0.2794)
							(mid 0.239121 -0.264521)
							(end 0.254 -0.2286)
						)
						(arc
							(start 0.254 0.2286)
							(mid 0.239121 0.264521)
							(end 0.2032 0.2794)
						)
					)
					(width 0)
					(fill yes)
				)
			)
		)
	)
	(footprint ""
		(layer "B.Cu")
		(at 90.424 -46.101 180)
		(property "Reference" "C146"
			(at 0 0 0)
			(layer "B.SilkS")
			(hide yes)
			(effects
				(font
					(size 1.27 1.27)
				)
				(justify mirror)
			)
		)
		(property "Value" "SC1U10V2KX-1GP"
			(at -1.1811 -2.7051 180)
			(unlocked yes)
			(layer "B.Fab")
			(hide yes)
			(effects
				(font
					(size 1.016 1.016)
					(thickness 0.1524)
				)
				(justify mirror)
			)
		)
		(property "Device Type" "C402H22"
			(at -1.1811 -4.2291 180)
			(unlocked yes)
			(layer "B.Fab")
			(hide yes)
			(effects
				(font
					(size 1.016 1.016)
					(thickness 0.1524)
				)
				(justify mirror)
			)
		)
		(duplicate_pad_numbers_are_jumpers no)
		(fp_rect
			(start 0.381 0.7366)
			(end -0.381 -0.7366)
			(stroke
				(width 0)
				(type default)
			)
			(fill no)
			(layer "B.CrtYd")
		)
		(fp_rect
			(start 0.381 0.7366)
			(end -0.381 -0.7366)
			(stroke
				(width 0)
				(type default)
			)
			(fill no)
			(layer "B.Fab")
		)
		(pad "1" smd custom
			(at 0 -0.4572)
			(size 0.1143 0.1143)
			(layers "B.Cu" "B.Mask" "B.Paste")
			(net "P3V3_CPU")
			(options
				(clearance outline)
				(anchor circle)
			)
			(primitives
				(gr_poly
					(pts
						(arc
							(start -0.254 0.1778)
							(mid -0.239121 0.213721)
							(end -0.2032 0.2286)
						)
						(arc
							(start 0.2032 0.2286)
							(mid 0.239121 0.213721)
							(end 0.254 0.1778)
						)
						(arc
							(start 0.254 -0.1778)
							(mid 0.239121 -0.213721)
							(end 0.2032 -0.2286)
						)
						(arc
							(start -0.2032 -0.2286)
							(mid -0.239121 -0.213721)
							(end -0.254 -0.1778)
						)
					)
					(width 0)
					(fill yes)
				)
			)
		)
		(pad "2" smd custom
			(at 0 0.4572)
			(size 0.1143 0.1143)
			(layers "B.Cu" "B.Mask" "B.Paste")
			(net "GND")
			(options
				(clearance outline)
				(anchor circle)
			)
			(primitives
				(gr_poly
					(pts
						(arc
							(start -0.254 0.1778)
							(mid -0.239121 0.213721)
							(end -0.2032 0.2286)
						)
						(arc
							(start 0.2032 0.2286)
							(mid 0.239121 0.213721)
							(end 0.254 0.1778)
						)
						(arc
							(start 0.254 -0.1778)
							(mid 0.239121 -0.213721)
							(end 0.2032 -0.2286)
						)
						(arc
							(start -0.2032 -0.2286)
							(mid -0.239121 -0.213721)
							(end -0.254 -0.1778)
						)
					)
					(width 0)
					(fill yes)
				)
			)
		)
	)
	(footprint ""
		(layer "B.Cu")
		(at 98.171 -43.18)
		(property "Reference" "C157"
			(at 0 0 0)
			(layer "B.SilkS")
			(hide yes)
			(effects
				(font
					(size 1.27 1.27)
				)
				(justify mirror)
			)
		)
		(property "Value" "SC1U10V2KX-1GP"
			(at -1.1811 -2.7051 0)
			(unlocked yes)
			(layer "B.Fab")
			(hide yes)
			(effects
				(font
					(size 1.016 1.016)
					(thickness 0.1524)
				)
				(justify mirror)
			)
		)
		(property "Device Type" "C402H22"
			(at -1.1811 -4.2291 0)
			(unlocked yes)
			(layer "B.Fab")
			(hide yes)
			(effects
				(font
					(size 1.016 1.016)
					(thickness 0.1524)
				)
				(justify mirror)
			)
		)
		(duplicate_pad_numbers_are_jumpers no)
		(fp_rect
			(start 0.381 0.7366)
			(end -0.381 -0.7366)
			(stroke
				(width 0)
				(type default)
			)
			(fill no)
			(layer "B.CrtYd")
		)
		(fp_rect
			(start 0.381 0.7366)
			(end -0.381 -0.7366)
			(stroke
				(width 0)
				(type default)
			)
			(fill no)
			(layer "B.Fab")
		)
		(pad "1" smd custom
			(at 0 -0.4572 180)
			(size 0.1143 0.1143)
			(layers "B.Cu" "B.Mask" "B.Paste")
			(net "P1V35")
			(options
				(clearance outline)
				(anchor circle)
			)
			(primitives
				(gr_poly
					(pts
						(arc
							(start -0.254 0.1778)
							(mid -0.239121 0.213721)
							(end -0.2032 0.2286)
						)
						(arc
							(start 0.2032 0.2286)
							(mid 0.239121 0.213721)
							(end 0.254 0.1778)
						)
						(arc
							(start 0.254 -0.1778)
							(mid 0.239121 -0.213721)
							(end 0.2032 -0.2286)
						)
						(arc
							(start -0.2032 -0.2286)
							(mid -0.239121 -0.213721)
							(end -0.254 -0.1778)
						)
					)
					(width 0)
					(fill yes)
				)
			)
		)
		(pad "2" smd custom
			(at 0 0.4572 180)
			(size 0.1143 0.1143)
			(layers "B.Cu" "B.Mask" "B.Paste")
			(net "GND")
			(options
				(clearance outline)
				(anchor circle)
			)
			(primitives
				(gr_poly
					(pts
						(arc
							(start -0.254 0.1778)
							(mid -0.239121 0.213721)
							(end -0.2032 0.2286)
						)
						(arc
							(start 0.2032 0.2286)
							(mid 0.239121 0.213721)
							(end 0.254 0.1778)
						)
						(arc
							(start 0.254 -0.1778)
							(mid 0.239121 -0.213721)
							(end 0.2032 -0.2286)
						)
						(arc
							(start -0.2032 -0.2286)
							(mid -0.239121 -0.213721)
							(end -0.254 -0.1778)
						)
					)
					(width 0)
					(fill yes)
				)
			)
		)
	)
	(footprint ""
		(layer "B.Cu")
		(at 133.35 -59.944 180)
		(property "Reference" "R231"
			(at 0 0 0)
			(layer "B.SilkS")
			(hide yes)
			(effects
				(font
					(size 1.27 1.27)
				)
				(justify mirror)
			)
		)
		(property "Value" "4K7R2F-GP"
			(at -0.064008 -3.993896 180)
			(unlocked yes)
			(layer "B.Fab")
			(hide yes)
			(effects
				(font
					(size 1.016 1.016)
					(thickness 0.1524)
				)
				(justify mirror)
			)
		)
		(property "Device Type" "R402H16"
			(at -0.064008 -5.517896 180)
			(unlocked yes)
			(layer "B.Fab")
			(hide yes)
			(effects
				(font
					(size 1.016 1.016)
					(thickness 0.1524)
				)
				(justify mirror)
			)
		)
		(duplicate_pad_numbers_are_jumpers no)
		(fp_rect
			(start 0.381 0.8382)
			(end -0.381 -0.8382)
			(stroke
				(width 0)
				(type default)
			)
			(fill no)
			(layer "B.CrtYd")
		)
		(fp_rect
			(start 0.381 0.8382)
			(end -0.381 -0.8382)
			(stroke
				(width 0)
				(type default)
			)
			(fill no)
			(layer "B.Fab")
		)
		(pad "1" smd custom
			(at 0 -0.4318)
			(size 0.127 0.127)
			(layers "B.Cu" "B.Mask" "B.Paste")
			(net "P3V3_STBY")
			(options
				(clearance outline)
				(anchor circle)
			)
			(primitives
				(gr_poly
					(pts
						(arc
							(start -0.2032 0.2794)
							(mid -0.239121 0.264521)
							(end -0.254 0.2286)
						)
						(arc
							(start -0.254 -0.2286)
							(mid -0.239121 -0.264521)
							(end -0.2032 -0.2794)
						)
						(arc
							(start 0.2032 -0.2794)
							(mid 0.239121 -0.264521)
							(end 0.254 -0.2286)
						)
						(arc
							(start 0.254 0.2286)
							(mid 0.239121 0.264521)
							(end 0.2032 0.2794)
						)
					)
					(width 0)
					(fill yes)
				)
			)
		)
		(pad "2" smd custom
			(at 0 0.4318)
			(size 0.127 0.127)
			(layers "B.Cu" "B.Mask" "B.Paste")
			(net "CHA_0_SA0")
			(options
				(clearance outline)
				(anchor circle)
			)
			(primitives
				(gr_poly
					(pts
						(arc
							(start -0.2032 0.2794)
							(mid -0.239121 0.264521)
							(end -0.254 0.2286)
						)
						(arc
							(start -0.254 -0.2286)
							(mid -0.239121 -0.264521)
							(end -0.2032 -0.2794)
						)
						(arc
							(start 0.2032 -0.2794)
							(mid 0.239121 -0.264521)
							(end 0.254 -0.2286)
						)
						(arc
							(start 0.254 0.2286)
							(mid 0.239121 0.264521)
							(end 0.2032 0.2794)
						)
					)
					(width 0)
					(fill yes)
				)
			)
		)
	)
	(footprint ""
		(layer "B.Cu")
		(at 96.647 -18.050002 180)
		(property "Reference" "C258"
			(at 0 0 0)
			(layer "B.SilkS")
			(hide yes)
			(effects
				(font
					(size 1.27 1.27)
				)
				(justify mirror)
			)
		)
		(property "Value" "SC1U25V3KX-GP"
			(at 0 -2.8194 180)
			(unlocked yes)
			(layer "B.Fab")
			(hide yes)
			(effects
				(font
					(size 1.016 1.016)
					(thickness 0.1524)
				)
				(justify mirror)
			)
		)
		(property "Device Type" "C603H36"
			(at 0 -4.3434 180)
			(unlocked yes)
			(layer "B.Fab")
			(hide yes)
			(effects
				(font
					(size 1.016 1.016)
					(thickness 0.1524)
				)
				(justify mirror)
			)
		)
		(duplicate_pad_numbers_are_jumpers no)
		(fp_line
			(start 0.4064 0)
			(end -0.4064 0)
			(stroke
				(width 0.2286)
				(type default)
			)
			(layer "B.SilkS")
		)
		(fp_rect
			(start 0.635 1.1811)
			(end -0.635 -1.1811)
			(stroke
				(width 0)
				(type default)
			)
			(fill no)
			(layer "B.CrtYd")
		)
		(fp_rect
			(start 0.635 1.1811)
			(end -0.635 -1.1811)
			(stroke
				(width 0)
				(type default)
			)
			(fill no)
			(layer "B.Fab")
		)
		(pad "1" smd custom
			(at 0 -0.6604)
			(size 0.19685 0.19685)
			(layers "B.Cu" "B.Mask" "B.Paste")
			(net "VCCACKDDR1")
			(options
				(clearance outline)
				(anchor circle)
			)
			(primitives
				(gr_poly
					(pts
						(arc
							(start 0.508 0.2921)
							(mid 0.478242 0.363942)
							(end 0.4064 0.3937)
						)
						(arc
							(start -0.4064 0.3937)
							(mid -0.478242 0.363942)
							(end -0.508 0.2921)
						)
						(arc
							(start -0.508 -0.2921)
							(mid -0.478242 -0.363942)
							(end -0.4064 -0.3937)
						)
						(arc
							(start 0.4064 -0.3937)
							(mid 0.478242 -0.363942)
							(end 0.508 -0.2921)
						)
					)
					(width 0)
					(fill yes)
				)
			)
		)
		(pad "2" smd custom
			(at 0 0.6604)
			(size 0.19685 0.19685)
			(layers "B.Cu" "B.Mask" "B.Paste")
			(net "GND")
			(options
				(clearance outline)
				(anchor circle)
			)
			(primitives
				(gr_poly
					(pts
						(arc
							(start 0.508 0.2921)
							(mid 0.478242 0.363942)
							(end 0.4064 0.3937)
						)
						(arc
							(start -0.4064 0.3937)
							(mid -0.478242 0.363942)
							(end -0.508 0.2921)
						)
						(arc
							(start -0.508 -0.2921)
							(mid -0.478242 -0.363942)
							(end -0.4064 -0.3937)
						)
						(arc
							(start 0.4064 -0.3937)
							(mid 0.478242 -0.363942)
							(end 0.508 -0.2921)
						)
					)
					(width 0)
					(fill yes)
				)
			)
		)
	)
	(footprint ""
		(layer "B.Cu")
		(at 89.154 -26.289 -90)
		(property "Reference" "C224"
			(at 0 0 90)
			(layer "B.SilkS")
			(hide yes)
			(effects
				(font
					(size 1.27 1.27)
				)
				(justify mirror)
			)
		)
		(property "Value" "SC1U10V2KX-1GP"
			(at -1.1811 -2.7051 270)
			(unlocked yes)
			(layer "B.Fab")
			(hide yes)
			(effects
				(font
					(size 1.016 1.016)
					(thickness 0.1524)
				)
				(justify mirror)
			)
		)
		(property "Device Type" "C402H22"
			(at -1.1811 -4.2291 270)
			(unlocked yes)
			(layer "B.Fab")
			(hide yes)
			(effects
				(font
					(size 1.016 1.016)
					(thickness 0.1524)
				)
				(justify mirror)
			)
		)
		(duplicate_pad_numbers_are_jumpers no)
		(fp_rect
			(start 0.381 0.7366)
			(end -0.381 -0.7366)
			(stroke
				(width 0)
				(type default)
			)
			(fill no)
			(layer "B.CrtYd")
		)
		(fp_rect
			(start 0.381 0.7366)
			(end -0.381 -0.7366)
			(stroke
				(width 0)
				(type default)
			)
			(fill no)
			(layer "B.Fab")
		)
		(pad "1" smd custom
			(at 0 -0.4572 90)
			(size 0.1143 0.1143)
			(layers "B.Cu" "B.Mask" "B.Paste")
			(net "P1V0")
			(options
				(clearance outline)
				(anchor circle)
			)
			(primitives
				(gr_poly
					(pts
						(arc
							(start -0.254 0.1778)
							(mid -0.239121 0.213721)
							(end -0.2032 0.2286)
						)
						(arc
							(start 0.2032 0.2286)
							(mid 0.239121 0.213721)
							(end 0.254 0.1778)
						)
						(arc
							(start 0.254 -0.1778)
							(mid 0.239121 -0.213721)
							(end 0.2032 -0.2286)
						)
						(arc
							(start -0.2032 -0.2286)
							(mid -0.239121 -0.213721)
							(end -0.254 -0.1778)
						)
					)
					(width 0)
					(fill yes)
				)
			)
		)
		(pad "2" smd custom
			(at 0 0.4572 90)
			(size 0.1143 0.1143)
			(layers "B.Cu" "B.Mask" "B.Paste")
			(net "GND")
			(options
				(clearance outline)
				(anchor circle)
			)
			(primitives
				(gr_poly
					(pts
						(arc
							(start -0.254 0.1778)
							(mid -0.239121 0.213721)
							(end -0.2032 0.2286)
						)
						(arc
							(start 0.2032 0.2286)
							(mid 0.239121 0.213721)
							(end 0.254 0.1778)
						)
						(arc
							(start 0.254 -0.1778)
							(mid 0.239121 -0.213721)
							(end 0.2032 -0.2286)
						)
						(arc
							(start -0.2032 -0.2286)
							(mid -0.239121 -0.213721)
							(end -0.254 -0.1778)
						)
					)
					(width 0)
					(fill yes)
				)
			)
		)
	)
)
